(kicad_pcb
	(version 20260206)
	(generator "pcbnew")
	(generator_version "10.0")
	(general
		(thickness 1.6)
		(legacy_teardrops no)
	)
	(paper "A4")
	(title_block
		(title "01162023_DA0F0TEBIF0_F0T_Expander_BD_F_brd_V02_OCP.brd")
		(comment 1 "Grand Teton / footprints 3413-3418 of 9728")
	)
	(layers
		(0 "F.Cu" signal "TOP")
		(4 "In1.Cu" signal "GND")
		(6 "In2.Cu" signal "VCC")
		(8 "In3.Cu" signal "VCC1")
		(10 "In4.Cu" signal "GND1")
		(12 "In5.Cu" signal "IN1")
		(14 "In6.Cu" signal "GND2")
		(16 "In7.Cu" signal "IN2")
		(18 "In8.Cu" signal "GND3")
		(20 "In9.Cu" signal "IN3")
		(22 "In10.Cu" signal "GND4")
		(24 "In11.Cu" signal "IN4")
		(26 "In12.Cu" signal "GND5")
		(28 "In13.Cu" signal "IN5")
		(30 "In14.Cu" signal "GND6")
		(32 "In15.Cu" signal "IN6")
		(34 "In16.Cu" signal "GND7")
		(2 "B.Cu" signal "BOTTOM")
		(9 "F.Adhes" user "F.Adhesive")
		(11 "B.Adhes" user "B.Adhesive")
		(13 "F.Paste" user "Package Geometry/Pastemask Top")
		(15 "B.Paste" user "Package Geometry/Pastemask Bottom")
		(5 "F.SilkS" user "Ref Des/Silkscreen Top")
		(7 "B.SilkS" user "Ref Des/Silkscreen Bottom")
		(1 "F.Mask" user "Board Geometry/Soldermask Top")
		(3 "B.Mask" user "Board Geometry/Soldermask Bottom")
		(17 "Dwgs.User" user "User.Drawings")
		(19 "Cmts.User" user "User.Comments")
		(21 "Eco1.User" user "User.Eco1")
		(23 "Eco2.User" user "User.Eco2")
		(25 "Edge.Cuts" user "Board Geometry/Outline")
		(27 "Margin" user)
		(31 "F.CrtYd" user "Package Geometry/Place Bound Top")
		(29 "B.CrtYd" user "Package Geometry/Place Bound Bottom")
		(35 "F.Fab" user "Ref Des/Assembly Top")
		(33 "B.Fab" user "Ref Des/Assembly Bottom")
	)
	(footprint ""
		(layer "F.Cu")
		(at 16.175736 -152.71115 -90)
		(property "Reference" "R688"
			(at 0 0 270)
			(layer "F.SilkS")
			(hide yes)
			(effects
				(font
					(size 1.27 1.27)
				)
			)
		)
		(property "Value" ""
			(at 0 0 270)
			(layer "F.Fab")
			(effects
				(font
					(size 1.27 1.27)
				)
			)
		)
		(duplicate_pad_numbers_are_jumpers no)
		(fp_line
			(start -0.7874 0.4064)
			(end -0.7874 -0.4064)
			(stroke
				(width 0.1524)
				(type default)
			)
			(layer "F.SilkS")
		)
		(fp_line
			(start 0.7874 0.4064)
			(end -0.7874 0.4064)
			(stroke
				(width 0.1524)
				(type default)
			)
			(layer "F.SilkS")
		)
		(fp_line
			(start -0.7874 -0.4064)
			(end 0.7874 -0.4064)
			(stroke
				(width 0.1524)
				(type default)
			)
			(layer "F.SilkS")
		)
		(fp_line
			(start 0.7874 -0.4064)
			(end 0.7874 0.4064)
			(stroke
				(width 0.1524)
				(type default)
			)
			(layer "F.SilkS")
		)
		(fp_line
			(start -0.67945 0.3048)
			(end -0.67945 -0.305054)
			(stroke
				(width 0.1)
				(type default)
			)
			(layer "F.Fab")
		)
		(fp_line
			(start -0.12065 0.3048)
			(end -0.67945 0.3048)
			(stroke
				(width 0.1)
				(type default)
			)
			(layer "F.Fab")
		)
		(fp_line
			(start 0.120396 0.3048)
			(end 0.120396 0.2794)
			(stroke
				(width 0.1)
				(type default)
			)
			(layer "F.Fab")
		)
		(fp_line
			(start 0.67945 0.3048)
			(end 0.120396 0.3048)
			(stroke
				(width 0.1)
				(type default)
			)
			(layer "F.Fab")
		)
		(fp_line
			(start -0.12065 0.2794)
			(end -0.12065 0.3048)
			(stroke
				(width 0.1)
				(type default)
			)
			(layer "F.Fab")
		)
		(fp_line
			(start 0.120396 0.2794)
			(end -0.12065 0.2794)
			(stroke
				(width 0.1)
				(type default)
			)
			(layer "F.Fab")
		)
		(fp_line
			(start -0.12065 -0.2794)
			(end 0.12065 -0.2794)
			(stroke
				(width 0.1)
				(type default)
			)
			(layer "F.Fab")
		)
		(fp_line
			(start 0.12065 -0.2794)
			(end 0.12065 -0.3048)
			(stroke
				(width 0.1)
				(type default)
			)
			(layer "F.Fab")
		)
		(fp_line
			(start 0.12065 -0.3048)
			(end 0.67945 -0.3048)
			(stroke
				(width 0.1)
				(type default)
			)
			(layer "F.Fab")
		)
		(fp_line
			(start 0.67945 -0.3048)
			(end 0.67945 0.3048)
			(stroke
				(width 0.1)
				(type default)
			)
			(layer "F.Fab")
		)
		(fp_line
			(start -0.67945 -0.305054)
			(end -0.12065 -0.305054)
			(stroke
				(width 0.1)
				(type default)
			)
			(layer "F.Fab")
		)
		(fp_line
			(start -0.12065 -0.305054)
			(end -0.12065 -0.2794)
			(stroke
				(width 0.1)
				(type default)
			)
			(layer "F.Fab")
		)
		(pad "1" smd circle
			(at -0.40005 0 270)
			(size 0 0)
			(layers "F.Cu" "F.Mask" "F.Paste")
			(net "SMB_BIC_I2C6_MUX_NIC_ADC_R_SDA")
		)
		(pad "2" smd circle
			(at 0.40005 0 270)
			(size 0 0)
			(layers "F.Cu" "F.Mask" "F.Paste")
			(net "SMB_NIC0_ADC_SDA")
		)
	)
	(footprint ""
		(layer "F.Cu")
		(at 137.420096 -198.091806)
		(property "Reference" "C2598"
			(at 0 0 0)
			(layer "F.SilkS")
			(hide yes)
			(effects
				(font
					(size 1.27 1.27)
				)
			)
		)
		(property "Value" ""
			(at 0 0 0)
			(layer "F.Fab")
			(effects
				(font
					(size 1.27 1.27)
				)
			)
		)
		(duplicate_pad_numbers_are_jumpers no)
		(fp_line
			(start -0.7874 -0.4064)
			(end 0.7874 -0.4064)
			(stroke
				(width 0.1524)
				(type default)
			)
			(layer "F.SilkS")
		)
		(fp_line
			(start -0.7874 0.4064)
			(end -0.7874 -0.4064)
			(stroke
				(width 0.1524)
				(type default)
			)
			(layer "F.SilkS")
		)
		(fp_line
			(start 0.7874 -0.4064)
			(end 0.7874 0.4064)
			(stroke
				(width 0.1524)
				(type default)
			)
			(layer "F.SilkS")
		)
		(fp_line
			(start 0.7874 0.4064)
			(end -0.7874 0.4064)
			(stroke
				(width 0.1524)
				(type default)
			)
			(layer "F.SilkS")
		)
		(fp_line
			(start -0.67945 -0.305054)
			(end -0.12065 -0.305054)
			(stroke
				(width 0.1)
				(type default)
			)
			(layer "F.Fab")
		)
		(fp_line
			(start -0.67945 0.3048)
			(end -0.67945 -0.305054)
			(stroke
				(width 0.1)
				(type default)
			)
			(layer "F.Fab")
		)
		(fp_line
			(start -0.12065 -0.305054)
			(end -0.12065 -0.2794)
			(stroke
				(width 0.1)
				(type default)
			)
			(layer "F.Fab")
		)
		(fp_line
			(start -0.12065 -0.2794)
			(end 0.12065 -0.2794)
			(stroke
				(width 0.1)
				(type default)
			)
			(layer "F.Fab")
		)
		(fp_line
			(start -0.12065 0.2794)
			(end -0.12065 0.3048)
			(stroke
				(width 0.1)
				(type default)
			)
			(layer "F.Fab")
		)
		(fp_line
			(start -0.12065 0.3048)
			(end -0.67945 0.3048)
			(stroke
				(width 0.1)
				(type default)
			)
			(layer "F.Fab")
		)
		(fp_line
			(start 0.120396 0.2794)
			(end -0.12065 0.2794)
			(stroke
				(width 0.1)
				(type default)
			)
			(layer "F.Fab")
		)
		(fp_line
			(start 0.120396 0.3048)
			(end 0.120396 0.2794)
			(stroke
				(width 0.1)
				(type default)
			)
			(layer "F.Fab")
		)
		(fp_line
			(start 0.12065 -0.3048)
			(end 0.67945 -0.3048)
			(stroke
				(width 0.1)
				(type default)
			)
			(layer "F.Fab")
		)
		(fp_line
			(start 0.12065 -0.2794)
			(end 0.12065 -0.3048)
			(stroke
				(width 0.1)
				(type default)
			)
			(layer "F.Fab")
		)
		(fp_line
			(start 0.67945 -0.3048)
			(end 0.67945 0.3048)
			(stroke
				(width 0.1)
				(type default)
			)
			(layer "F.Fab")
		)
		(fp_line
			(start 0.67945 0.3048)
			(end 0.120396 0.3048)
			(stroke
				(width 0.1)
				(type default)
			)
			(layer "F.Fab")
		)
		(pad "1" smd circle
			(at -0.40005 0)
			(size 0 0)
			(layers "F.Cu" "F.Mask" "F.Paste")
			(net "OSC_CLI_OUT")
		)
		(pad "2" smd circle
			(at 0.40005 0)
			(size 0 0)
			(layers "F.Cu" "F.Mask" "F.Paste")
			(net "GND")
		)
	)
	(footprint ""
		(layer "F.Cu")
		(at 376.809 -177.19802)
		(property "Reference" "R4715"
			(at 0 0 0)
			(layer "F.SilkS")
			(hide yes)
			(effects
				(font
					(size 1.27 1.27)
				)
			)
		)
		(property "Value" ""
			(at 0 0 0)
			(layer "F.Fab")
			(effects
				(font
					(size 1.27 1.27)
				)
			)
		)
		(duplicate_pad_numbers_are_jumpers no)
		(fp_line
			(start -0.7874 -0.4064)
			(end 0.7874 -0.4064)
			(stroke
				(width 0.1524)
				(type default)
			)
			(layer "F.SilkS")
		)
		(fp_line
			(start -0.7874 0.4064)
			(end -0.7874 -0.4064)
			(stroke
				(width 0.1524)
				(type default)
			)
			(layer "F.SilkS")
		)
		(fp_line
			(start 0.7874 -0.4064)
			(end 0.7874 0.4064)
			(stroke
				(width 0.1524)
				(type default)
			)
			(layer "F.SilkS")
		)
		(fp_line
			(start 0.7874 0.4064)
			(end -0.7874 0.4064)
			(stroke
				(width 0.1524)
				(type default)
			)
			(layer "F.SilkS")
		)
		(fp_line
			(start -0.67945 -0.305054)
			(end -0.12065 -0.305054)
			(stroke
				(width 0.1)
				(type default)
			)
			(layer "F.Fab")
		)
		(fp_line
			(start -0.67945 0.3048)
			(end -0.67945 -0.305054)
			(stroke
				(width 0.1)
				(type default)
			)
			(layer "F.Fab")
		)
		(fp_line
			(start -0.12065 -0.305054)
			(end -0.12065 -0.2794)
			(stroke
				(width 0.1)
				(type default)
			)
			(layer "F.Fab")
		)
		(fp_line
			(start -0.12065 -0.2794)
			(end 0.12065 -0.2794)
			(stroke
				(width 0.1)
				(type default)
			)
			(layer "F.Fab")
		)
		(fp_line
			(start -0.12065 0.2794)
			(end -0.12065 0.3048)
			(stroke
				(width 0.1)
				(type default)
			)
			(layer "F.Fab")
		)
		(fp_line
			(start -0.12065 0.3048)
			(end -0.67945 0.3048)
			(stroke
				(width 0.1)
				(type default)
			)
			(layer "F.Fab")
		)
		(fp_line
			(start 0.120396 0.2794)
			(end -0.12065 0.2794)
			(stroke
				(width 0.1)
				(type default)
			)
			(layer "F.Fab")
		)
		(fp_line
			(start 0.120396 0.3048)
			(end 0.120396 0.2794)
			(stroke
				(width 0.1)
				(type default)
			)
			(layer "F.Fab")
		)
		(fp_line
			(start 0.12065 -0.3048)
			(end 0.67945 -0.3048)
			(stroke
				(width 0.1)
				(type default)
			)
			(layer "F.Fab")
		)
		(fp_line
			(start 0.12065 -0.2794)
			(end 0.12065 -0.3048)
			(stroke
				(width 0.1)
				(type default)
			)
			(layer "F.Fab")
		)
		(fp_line
			(start 0.67945 -0.3048)
			(end 0.67945 0.3048)
			(stroke
				(width 0.1)
				(type default)
			)
			(layer "F.Fab")
		)
		(fp_line
			(start 0.67945 0.3048)
			(end 0.120396 0.3048)
			(stroke
				(width 0.1)
				(type default)
			)
			(layer "F.Fab")
		)
		(pad "1" smd circle
			(at -0.40005 0)
			(size 0 0)
			(layers "F.Cu" "F.Mask" "F.Paste")
			(net "RST_PEX_NIC3_PERST_N")
		)
		(pad "2" smd circle
			(at 0.40005 0)
			(size 0 0)
			(layers "F.Cu" "F.Mask" "F.Paste")
			(net "RST_PEX_NIC3_PERST_R_N")
		)
	)
	(footprint ""
		(layer "F.Cu")
		(at 194.343782 -43.85691)
		(property "Reference" "R574"
			(at 0 0 0)
			(layer "F.SilkS")
			(hide yes)
			(effects
				(font
					(size 1.27 1.27)
				)
			)
		)
		(property "Value" ""
			(at 0 0 0)
			(layer "F.Fab")
			(effects
				(font
					(size 1.27 1.27)
				)
			)
		)
		(duplicate_pad_numbers_are_jumpers no)
		(fp_line
			(start -0.7874 -0.4064)
			(end 0.7874 -0.4064)
			(stroke
				(width 0.1524)
				(type default)
			)
			(layer "F.SilkS")
		)
		(fp_line
			(start -0.7874 0.4064)
			(end -0.7874 -0.4064)
			(stroke
				(width 0.1524)
				(type default)
			)
			(layer "F.SilkS")
		)
		(fp_line
			(start 0.7874 -0.4064)
			(end 0.7874 0.4064)
			(stroke
				(width 0.1524)
				(type default)
			)
			(layer "F.SilkS")
		)
		(fp_line
			(start 0.7874 0.4064)
			(end -0.7874 0.4064)
			(stroke
				(width 0.1524)
				(type default)
			)
			(layer "F.SilkS")
		)
		(fp_line
			(start -0.67945 -0.305054)
			(end -0.12065 -0.305054)
			(stroke
				(width 0.1)
				(type default)
			)
			(layer "F.Fab")
		)
		(fp_line
			(start -0.67945 0.3048)
			(end -0.67945 -0.305054)
			(stroke
				(width 0.1)
				(type default)
			)
			(layer "F.Fab")
		)
		(fp_line
			(start -0.12065 -0.305054)
			(end -0.12065 -0.2794)
			(stroke
				(width 0.1)
				(type default)
			)
			(layer "F.Fab")
		)
		(fp_line
			(start -0.12065 -0.2794)
			(end 0.12065 -0.2794)
			(stroke
				(width 0.1)
				(type default)
			)
			(layer "F.Fab")
		)
		(fp_line
			(start -0.12065 0.2794)
			(end -0.12065 0.3048)
			(stroke
				(width 0.1)
				(type default)
			)
			(layer "F.Fab")
		)
		(fp_line
			(start -0.12065 0.3048)
			(end -0.67945 0.3048)
			(stroke
				(width 0.1)
				(type default)
			)
			(layer "F.Fab")
		)
		(fp_line
			(start 0.120396 0.2794)
			(end -0.12065 0.2794)
			(stroke
				(width 0.1)
				(type default)
			)
			(layer "F.Fab")
		)
		(fp_line
			(start 0.120396 0.3048)
			(end 0.120396 0.2794)
			(stroke
				(width 0.1)
				(type default)
			)
			(layer "F.Fab")
		)
		(fp_line
			(start 0.12065 -0.3048)
			(end 0.67945 -0.3048)
			(stroke
				(width 0.1)
				(type default)
			)
			(layer "F.Fab")
		)
		(fp_line
			(start 0.12065 -0.2794)
			(end 0.12065 -0.3048)
			(stroke
				(width 0.1)
				(type default)
			)
			(layer "F.Fab")
		)
		(fp_line
			(start 0.67945 -0.3048)
			(end 0.67945 0.3048)
			(stroke
				(width 0.1)
				(type default)
			)
			(layer "F.Fab")
		)
		(fp_line
			(start 0.67945 0.3048)
			(end 0.120396 0.3048)
			(stroke
				(width 0.1)
				(type default)
			)
			(layer "F.Fab")
		)
		(pad "1" smd circle
			(at -0.40005 0)
			(size 0 0)
			(layers "F.Cu" "F.Mask" "F.Paste")
			(net "SSD6_ADC_A1")
		)
		(pad "2" smd circle
			(at 0.40005 0)
			(size 0 0)
			(layers "F.Cu" "F.Mask" "F.Paste")
			(net "GND")
		)
	)
	(footprint ""
		(layer "F.Cu")
		(at 385.850384 -252.356874 -90)
		(property "Reference" "R1435"
			(at 0 0 270)
			(layer "F.SilkS")
			(hide yes)
			(effects
				(font
					(size 1.27 1.27)
				)
			)
		)
		(property "Value" ""
			(at 0 0 270)
			(layer "F.Fab")
			(effects
				(font
					(size 1.27 1.27)
				)
			)
		)
		(duplicate_pad_numbers_are_jumpers no)
		(fp_line
			(start -0.7874 0.4064)
			(end -0.7874 -0.4064)
			(stroke
				(width 0.1524)
				(type default)
			)
			(layer "F.SilkS")
		)
		(fp_line
			(start 0.7874 0.4064)
			(end -0.7874 0.4064)
			(stroke
				(width 0.1524)
				(type default)
			)
			(layer "F.SilkS")
		)
		(fp_line
			(start -0.7874 -0.4064)
			(end 0.7874 -0.4064)
			(stroke
				(width 0.1524)
				(type default)
			)
			(layer "F.SilkS")
		)
		(fp_line
			(start 0.7874 -0.4064)
			(end 0.7874 0.4064)
			(stroke
				(width 0.1524)
				(type default)
			)
			(layer "F.SilkS")
		)
		(fp_line
			(start -0.67945 0.3048)
			(end -0.67945 -0.305054)
			(stroke
				(width 0.1)
				(type default)
			)
			(layer "F.Fab")
		)
		(fp_line
			(start -0.12065 0.3048)
			(end -0.67945 0.3048)
			(stroke
				(width 0.1)
				(type default)
			)
			(layer "F.Fab")
		)
		(fp_line
			(start 0.120396 0.3048)
			(end 0.120396 0.2794)
			(stroke
				(width 0.1)
				(type default)
			)
			(layer "F.Fab")
		)
		(fp_line
			(start 0.67945 0.3048)
			(end 0.120396 0.3048)
			(stroke
				(width 0.1)
				(type default)
			)
			(layer "F.Fab")
		)
		(fp_line
			(start -0.12065 0.2794)
			(end -0.12065 0.3048)
			(stroke
				(width 0.1)
				(type default)
			)
			(layer "F.Fab")
		)
		(fp_line
			(start 0.120396 0.2794)
			(end -0.12065 0.2794)
			(stroke
				(width 0.1)
				(type default)
			)
			(layer "F.Fab")
		)
		(fp_line
			(start -0.12065 -0.2794)
			(end 0.12065 -0.2794)
			(stroke
				(width 0.1)
				(type default)
			)
			(layer "F.Fab")
		)
		(fp_line
			(start 0.12065 -0.2794)
			(end 0.12065 -0.3048)
			(stroke
				(width 0.1)
				(type default)
			)
			(layer "F.Fab")
		)
		(fp_line
			(start 0.12065 -0.3048)
			(end 0.67945 -0.3048)
			(stroke
				(width 0.1)
				(type default)
			)
			(layer "F.Fab")
		)
		(fp_line
			(start 0.67945 -0.3048)
			(end 0.67945 0.3048)
			(stroke
				(width 0.1)
				(type default)
			)
			(layer "F.Fab")
		)
		(fp_line
			(start -0.67945 -0.305054)
			(end -0.12065 -0.305054)
			(stroke
				(width 0.1)
				(type default)
			)
			(layer "F.Fab")
		)
		(fp_line
			(start -0.12065 -0.305054)
			(end -0.12065 -0.2794)
			(stroke
				(width 0.1)
				(type default)
			)
			(layer "F.Fab")
		)
		(pad "1" smd circle
			(at -0.40005 0 270)
			(size 0 0)
			(layers "F.Cu" "F.Mask" "F.Paste")
			(net "GND")
		)
		(pad "2" smd circle
			(at 0.40005 0 270)
			(size 0 0)
			(layers "F.Cu" "F.Mask" "F.Paste")
			(net "PEX3_MODE_SEL10")
		)
	)
	(footprint ""
		(layer "F.Cu")
		(at 270.807942 -158.3944 180)
		(property "Reference" "R215"
			(at 0 0 180)
			(layer "F.SilkS")
			(hide yes)
			(effects
				(font
					(size 1.27 1.27)
				)
			)
		)
		(property "Value" ""
			(at 0 0 180)
			(layer "F.Fab")
			(effects
				(font
					(size 1.27 1.27)
				)
			)
		)
		(duplicate_pad_numbers_are_jumpers no)
		(fp_line
			(start 0.7874 0.4064)
			(end -0.7874 0.4064)
			(stroke
				(width 0.1524)
				(type default)
			)
			(layer "F.SilkS")
		)
		(fp_line
			(start 0.7874 -0.4064)
			(end 0.7874 0.4064)
			(stroke
				(width 0.1524)
				(type default)
			)
			(layer "F.SilkS")
		)
		(fp_line
			(start -0.7874 0.4064)
			(end -0.7874 -0.4064)
			(stroke
				(width 0.1524)
				(type default)
			)
			(layer "F.SilkS")
		)
		(fp_line
			(start -0.7874 -0.4064)
			(end 0.7874 -0.4064)
			(stroke
				(width 0.1524)
				(type default)
			)
			(layer "F.SilkS")
		)
		(fp_line
			(start 0.67945 0.3048)
			(end 0.120396 0.3048)
			(stroke
				(width 0.1)
				(type default)
			)
			(layer "F.Fab")
		)
		(fp_line
			(start 0.67945 -0.3048)
			(end 0.67945 0.3048)
			(stroke
				(width 0.1)
				(type default)
			)
			(layer "F.Fab")
		)
		(fp_line
			(start 0.12065 -0.2794)
			(end 0.12065 -0.3048)
			(stroke
				(width 0.1)
				(type default)
			)
			(layer "F.Fab")
		)
		(fp_line
			(start 0.12065 -0.3048)
			(end 0.67945 -0.3048)
			(stroke
				(width 0.1)
				(type default)
			)
			(layer "F.Fab")
		)
		(fp_line
			(start 0.120396 0.3048)
			(end 0.120396 0.2794)
			(stroke
				(width 0.1)
				(type default)
			)
			(layer "F.Fab")
		)
		(fp_line
			(start 0.120396 0.2794)
			(end -0.12065 0.2794)
			(stroke
				(width 0.1)
				(type default)
			)
			(layer "F.Fab")
		)
		(fp_line
			(start -0.12065 0.3048)
			(end -0.67945 0.3048)
			(stroke
				(width 0.1)
				(type default)
			)
			(layer "F.Fab")
		)
		(fp_line
			(start -0.12065 0.2794)
			(end -0.12065 0.3048)
			(stroke
				(width 0.1)
				(type default)
			)
			(layer "F.Fab")
		)
		(fp_line
			(start -0.12065 -0.2794)
			(end 0.12065 -0.2794)
			(stroke
				(width 0.1)
				(type default)
			)
			(layer "F.Fab")
		)
		(fp_line
			(start -0.12065 -0.305054)
			(end -0.12065 -0.2794)
			(stroke
				(width 0.1)
				(type default)
			)
			(layer "F.Fab")
		)
		(fp_line
			(start -0.67945 0.3048)
			(end -0.67945 -0.305054)
			(stroke
				(width 0.1)
				(type default)
			)
			(layer "F.Fab")
		)
		(fp_line
			(start -0.67945 -0.305054)
			(end -0.12065 -0.305054)
			(stroke
				(width 0.1)
				(type default)
			)
			(layer "F.Fab")
		)
		(pad "1" smd circle
			(at -0.40005 0 180)
			(size 0 0)
			(layers "F.Cu" "F.Mask" "F.Paste")
			(net "NIC4_LD_N")
		)
		(pad "2" smd circle
			(at 0.40005 0 180)
			(size 0 0)
			(layers "F.Cu" "F.Mask" "F.Paste")
			(net "P3V3_NIC4")
		)
	)
)
